1 2 3 4 5 6 7 8 9 10 11 12 13 14
1413121110987654321
DRAWING NO.
SCALE DWG
DO NOT 
MODEL NAME
APPD
CKD
DSN
DRN
SHEET
SIGNDESCRIPTION DATE
Wiwynn Corporation
A
B
C
D
E
G
F
H
I
J
A
B
C
D
E
F
G
H
I
J
MATERIAL
FINISH
OF
DIM IN  mm
REV
145.00
0.00
119.00
50.50
29.50
94.31
39.68
2-29.48
0.00
3.70
0.00
9.92
4- (NO TRACE AT ALL LAYERS)6.00
(NPTH)2.41
(NPTH)2.55
(NO TRACE AT ALL LAYERS)7.00
4- (NO TRACE AT ALL LAYERS)6.00
4- (NPTH)3.00
210.00
0.00
95.00
151.50
135.00
198.50
85.00
125.00
131.43
126.93
135.93
3-9.50
3-200.50
126.93
131.43
135.93
(PTH)3.70
(PTH)2.10
(PTH)1.55
(PTH)2.10
(PTH)3.70
(PTH)1.55
(PAD)(NO TRACE AT ALL LAYERS EXCEPT GND)18.00
(PAD)(NO TRACE AT ALL LAYERS EXCEPT GND)18.00
(PAD)(NO TRACE AT ALL LAYERS EXCEPT GND)18.00
(PAD)(NO TRACE AT ALL LAYERS EXCEPT GND)18.00
(PAD)(NO TRACE AT ALL LAYERS)9.50
(PAD)(NO TRACE AT ALL LAYERS)9.50
(PTH)3.50
(PTH)3.50
(PAD)(NO TRACE AT ALL LAYERS)9.50
(PAD)(NO TRACE AT ALL LAYERS)9.50
BryceCanyon
CD  
Jess Wang 6/6
2017
Jess Wang 6/6
2017
Bryce Canyon Storage Controller Card
FR4 T=1.6mm 
NA 
1 1 Lenny Kao 
Lenny Kao 
6/6
2017
6/6
2017
COMPONENT SIDE SOLDER SIDE
16316-1 VERSION A 2017-06-06
SEE DETAIL  BSEE DETAIL  A
DETAIL  B
SCALE  3.000
DETAIL  A
SCALE  3.000